(kicad_pcb
	(version 20260206)
	(generator "pcbnew")
	(generator_version "10.0")
	(general
		(thickness 1.6)
		(legacy_teardrops no)
	)
	(paper "A4")
	(title_block
		(title "03242023_DA0F0TMBIJ0_F0T_Motherboard_J_brd_V01_OCP.brd")
		(comment 1 "Grand Teton / footprints 147-154 of 6105")
	)
	(layers
		(0 "F.Cu" signal "TOP")
		(4 "In1.Cu" signal "GND")
		(6 "In2.Cu" signal "IN1")
		(8 "In3.Cu" signal "GND1")
		(10 "In4.Cu" signal "IN2")
		(12 "In5.Cu" signal "GND2")
		(14 "In6.Cu" signal "IN3")
		(16 "In7.Cu" signal "GND3")
		(18 "In8.Cu" signal "VCC")
		(20 "In9.Cu" signal "VCC1")
		(22 "In10.Cu" signal "GND4")
		(24 "In11.Cu" signal "IN4")
		(26 "In12.Cu" signal "GND5")
		(28 "In13.Cu" signal "IN5")
		(30 "In14.Cu" signal "GND6")
		(32 "In15.Cu" signal "IN6")
		(34 "In16.Cu" signal "GND7")
		(2 "B.Cu" signal "BOTTOM")
		(9 "F.Adhes" user "F.Adhesive")
		(11 "B.Adhes" user "B.Adhesive")
		(13 "F.Paste" user "Package Geometry/Pastemask Top")
		(15 "B.Paste" user "Package Geometry/Pastemask Bottom")
		(5 "F.SilkS" user "Ref Des/Silkscreen Top")
		(7 "B.SilkS" user "Ref Des/Silkscreen Bottom")
		(1 "F.Mask" user "Board Geometry/Soldermask Top")
		(3 "B.Mask" user "Board Geometry/Soldermask Bottom")
		(17 "Dwgs.User" user "User.Drawings")
		(19 "Cmts.User" user "User.Comments")
		(21 "Eco1.User" user "User.Eco1")
		(23 "Eco2.User" user "User.Eco2")
		(25 "Edge.Cuts" user "Board Geometry/Outline")
		(27 "Margin" user)
		(31 "F.CrtYd" user "Package Geometry/Place Bound Top")
		(29 "B.CrtYd" user "Package Geometry/Place Bound Bottom")
		(35 "F.Fab" user "Ref Des/Assembly Top")
		(33 "B.Fab" user "Ref Des/Assembly Bottom")
	)
	(footprint ""
		(layer "F.Cu")
		(at 197.177406 -40.138604)
		(property "Reference" "R3996"
			(at 0 0 0)
			(layer "F.SilkS")
			(hide yes)
			(effects
				(font
					(size 1.27 1.27)
				)
			)
		)
		(property "Value" ""
			(at 0 0 0)
			(layer "F.Fab")
			(effects
				(font
					(size 1.27 1.27)
				)
			)
		)
		(duplicate_pad_numbers_are_jumpers no)
		(fp_line
			(start -0.7874 -0.4064)
			(end 0.7874 -0.4064)
			(stroke
				(width 0.1524)
				(type default)
			)
			(layer "F.SilkS")
		)
		(fp_line
			(start -0.7874 0.4064)
			(end -0.7874 -0.4064)
			(stroke
				(width 0.1524)
				(type default)
			)
			(layer "F.SilkS")
		)
		(fp_line
			(start 0.7874 -0.4064)
			(end 0.7874 0.4064)
			(stroke
				(width 0.1524)
				(type default)
			)
			(layer "F.SilkS")
		)
		(fp_line
			(start 0.7874 0.4064)
			(end -0.7874 0.4064)
			(stroke
				(width 0.1524)
				(type default)
			)
			(layer "F.SilkS")
		)
		(fp_line
			(start -0.67945 -0.305054)
			(end -0.12065 -0.305054)
			(stroke
				(width 0.1)
				(type default)
			)
			(layer "F.Fab")
		)
		(fp_line
			(start -0.67945 0.3048)
			(end -0.67945 -0.305054)
			(stroke
				(width 0.1)
				(type default)
			)
			(layer "F.Fab")
		)
		(fp_line
			(start -0.12065 -0.305054)
			(end -0.12065 -0.2794)
			(stroke
				(width 0.1)
				(type default)
			)
			(layer "F.Fab")
		)
		(fp_line
			(start -0.12065 -0.2794)
			(end 0.12065 -0.2794)
			(stroke
				(width 0.1)
				(type default)
			)
			(layer "F.Fab")
		)
		(fp_line
			(start -0.12065 0.2794)
			(end -0.12065 0.3048)
			(stroke
				(width 0.1)
				(type default)
			)
			(layer "F.Fab")
		)
		(fp_line
			(start -0.12065 0.3048)
			(end -0.67945 0.3048)
			(stroke
				(width 0.1)
				(type default)
			)
			(layer "F.Fab")
		)
		(fp_line
			(start 0.120396 0.2794)
			(end -0.12065 0.2794)
			(stroke
				(width 0.1)
				(type default)
			)
			(layer "F.Fab")
		)
		(fp_line
			(start 0.120396 0.3048)
			(end 0.120396 0.2794)
			(stroke
				(width 0.1)
				(type default)
			)
			(layer "F.Fab")
		)
		(fp_line
			(start 0.12065 -0.3048)
			(end 0.67945 -0.3048)
			(stroke
				(width 0.1)
				(type default)
			)
			(layer "F.Fab")
		)
		(fp_line
			(start 0.12065 -0.2794)
			(end 0.12065 -0.3048)
			(stroke
				(width 0.1)
				(type default)
			)
			(layer "F.Fab")
		)
		(fp_line
			(start 0.67945 -0.3048)
			(end 0.67945 0.3048)
			(stroke
				(width 0.1)
				(type default)
			)
			(layer "F.Fab")
		)
		(fp_line
			(start 0.67945 0.3048)
			(end 0.120396 0.3048)
			(stroke
				(width 0.1)
				(type default)
			)
			(layer "F.Fab")
		)
		(pad "1" smd circle
			(at -0.40005 0)
			(size 0 0)
			(layers "F.Cu" "F.Mask" "F.Paste")
			(net "VIRTUAL_RESEAT_FPGA_N")
		)
		(pad "2" smd circle
			(at 0.40005 0)
			(size 0 0)
			(layers "F.Cu" "F.Mask" "F.Paste")
			(net "P12V_SCM_EN")
		)
	)
	(footprint ""
		(layer "F.Cu")
		(at 439.262266 -123.664726 180)
		(property "Reference" "R1717"
			(at 0 0 180)
			(layer "F.SilkS")
			(hide yes)
			(effects
				(font
					(size 1.27 1.27)
				)
			)
		)
		(property "Value" ""
			(at 0 0 180)
			(layer "F.Fab")
			(effects
				(font
					(size 1.27 1.27)
				)
			)
		)
		(duplicate_pad_numbers_are_jumpers no)
		(fp_line
			(start 0.7874 0.4064)
			(end -0.7874 0.4064)
			(stroke
				(width 0.1524)
				(type default)
			)
			(layer "F.SilkS")
		)
		(fp_line
			(start 0.7874 -0.4064)
			(end 0.7874 0.4064)
			(stroke
				(width 0.1524)
				(type default)
			)
			(layer "F.SilkS")
		)
		(fp_line
			(start -0.7874 0.4064)
			(end -0.7874 -0.4064)
			(stroke
				(width 0.1524)
				(type default)
			)
			(layer "F.SilkS")
		)
		(fp_line
			(start -0.7874 -0.4064)
			(end 0.7874 -0.4064)
			(stroke
				(width 0.1524)
				(type default)
			)
			(layer "F.SilkS")
		)
		(fp_line
			(start 0.67945 0.3048)
			(end 0.120396 0.3048)
			(stroke
				(width 0.1)
				(type default)
			)
			(layer "F.Fab")
		)
		(fp_line
			(start 0.67945 -0.3048)
			(end 0.67945 0.3048)
			(stroke
				(width 0.1)
				(type default)
			)
			(layer "F.Fab")
		)
		(fp_line
			(start 0.12065 -0.2794)
			(end 0.12065 -0.3048)
			(stroke
				(width 0.1)
				(type default)
			)
			(layer "F.Fab")
		)
		(fp_line
			(start 0.12065 -0.3048)
			(end 0.67945 -0.3048)
			(stroke
				(width 0.1)
				(type default)
			)
			(layer "F.Fab")
		)
		(fp_line
			(start 0.120396 0.3048)
			(end 0.120396 0.2794)
			(stroke
				(width 0.1)
				(type default)
			)
			(layer "F.Fab")
		)
		(fp_line
			(start 0.120396 0.2794)
			(end -0.12065 0.2794)
			(stroke
				(width 0.1)
				(type default)
			)
			(layer "F.Fab")
		)
		(fp_line
			(start -0.12065 0.3048)
			(end -0.67945 0.3048)
			(stroke
				(width 0.1)
				(type default)
			)
			(layer "F.Fab")
		)
		(fp_line
			(start -0.12065 0.2794)
			(end -0.12065 0.3048)
			(stroke
				(width 0.1)
				(type default)
			)
			(layer "F.Fab")
		)
		(fp_line
			(start -0.12065 -0.2794)
			(end 0.12065 -0.2794)
			(stroke
				(width 0.1)
				(type default)
			)
			(layer "F.Fab")
		)
		(fp_line
			(start -0.12065 -0.305054)
			(end -0.12065 -0.2794)
			(stroke
				(width 0.1)
				(type default)
			)
			(layer "F.Fab")
		)
		(fp_line
			(start -0.67945 0.3048)
			(end -0.67945 -0.305054)
			(stroke
				(width 0.1)
				(type default)
			)
			(layer "F.Fab")
		)
		(fp_line
			(start -0.67945 -0.305054)
			(end -0.12065 -0.305054)
			(stroke
				(width 0.1)
				(type default)
			)
			(layer "F.Fab")
		)
		(pad "1" smd circle
			(at -0.40005 0 180)
			(size 0 0)
			(layers "F.Cu" "F.Mask" "F.Paste")
			(net "PVNN_TERM_CPU0")
		)
		(pad "2" smd circle
			(at 0.40005 0 180)
			(size 0 0)
			(layers "F.Cu" "F.Mask" "F.Paste")
			(net "SVID_CLK1_CPU0_R")
		)
	)
	(footprint ""
		(layer "F.Cu")
		(at 129.319274 -402.371052 -90)
		(property "Reference" "C749"
			(at 0 0 270)
			(layer "F.SilkS")
			(hide yes)
			(effects
				(font
					(size 1.27 1.27)
				)
			)
		)
		(property "Value" ""
			(at 0 0 270)
			(layer "F.Fab")
			(effects
				(font
					(size 1.27 1.27)
				)
			)
		)
		(duplicate_pad_numbers_are_jumpers no)
		(fp_line
			(start -0.299974 0.150114)
			(end -0.299974 -0.150114)
			(stroke
				(width 0.1)
				(type default)
			)
			(layer "F.Fab")
		)
		(fp_line
			(start 0.299974 0.150114)
			(end -0.299974 0.150114)
			(stroke
				(width 0.1)
				(type default)
			)
			(layer "F.Fab")
		)
		(fp_line
			(start -0.299974 -0.150114)
			(end 0.299974 -0.150114)
			(stroke
				(width 0.1)
				(type default)
			)
			(layer "F.Fab")
		)
		(fp_line
			(start 0.299974 -0.150114)
			(end 0.299974 0.150114)
			(stroke
				(width 0.1)
				(type default)
			)
			(layer "F.Fab")
		)
		(pad "1" smd rect
			(at -0.2667 0 270)
			(size 0.3048 0.381)
			(layers "F.Cu" "F.Mask" "F.Paste")
			(net "P5E_CPU1_PE2_TX_C_DP<12>")
		)
		(pad "2" smd rect
			(at 0.2667 0 270)
			(size 0.3048 0.381)
			(layers "F.Cu" "F.Mask" "F.Paste")
			(net "P5E_CPU1_PE2_TX_DP<12>")
		)
	)
	(footprint ""
		(layer "F.Cu")
		(at 334.587088 -402.371052 -90)
		(property "Reference" "C1558"
			(at 0 0 270)
			(layer "F.SilkS")
			(hide yes)
			(effects
				(font
					(size 1.27 1.27)
				)
			)
		)
		(property "Value" ""
			(at 0 0 270)
			(layer "F.Fab")
			(effects
				(font
					(size 1.27 1.27)
				)
			)
		)
		(duplicate_pad_numbers_are_jumpers no)
		(fp_line
			(start -0.299974 0.150114)
			(end -0.299974 -0.150114)
			(stroke
				(width 0.1)
				(type default)
			)
			(layer "F.Fab")
		)
		(fp_line
			(start 0.299974 0.150114)
			(end -0.299974 0.150114)
			(stroke
				(width 0.1)
				(type default)
			)
			(layer "F.Fab")
		)
		(fp_line
			(start -0.299974 -0.150114)
			(end 0.299974 -0.150114)
			(stroke
				(width 0.1)
				(type default)
			)
			(layer "F.Fab")
		)
		(fp_line
			(start 0.299974 -0.150114)
			(end 0.299974 0.150114)
			(stroke
				(width 0.1)
				(type default)
			)
			(layer "F.Fab")
		)
		(pad "1" smd rect
			(at -0.2667 0 270)
			(size 0.3048 0.381)
			(layers "F.Cu" "F.Mask" "F.Paste")
			(net "P5E_CPU0_PE4_TX_C_DN<10>")
		)
		(pad "2" smd rect
			(at 0.2667 0 270)
			(size 0.3048 0.381)
			(layers "F.Cu" "F.Mask" "F.Paste")
			(net "P5E_CPU0_PE4_TX_DN<10>")
		)
	)
	(footprint ""
		(layer "F.Cu")
		(at 39.394892 -397.42491 90)
		(property "Reference" "R4650"
			(at 0 0 90)
			(layer "F.SilkS")
			(hide yes)
			(effects
				(font
					(size 1.27 1.27)
				)
			)
		)
		(property "Value" ""
			(at 0 0 90)
			(layer "F.Fab")
			(effects
				(font
					(size 1.27 1.27)
				)
			)
		)
		(duplicate_pad_numbers_are_jumpers no)
		(fp_line
			(start 0.7874 -0.4064)
			(end 0.7874 0.4064)
			(stroke
				(width 0.1524)
				(type default)
			)
			(layer "F.SilkS")
		)
		(fp_line
			(start -0.7874 -0.4064)
			(end 0.7874 -0.4064)
			(stroke
				(width 0.1524)
				(type default)
			)
			(layer "F.SilkS")
		)
		(fp_line
			(start 0.7874 0.4064)
			(end -0.7874 0.4064)
			(stroke
				(width 0.1524)
				(type default)
			)
			(layer "F.SilkS")
		)
		(fp_line
			(start -0.7874 0.4064)
			(end -0.7874 -0.4064)
			(stroke
				(width 0.1524)
				(type default)
			)
			(layer "F.SilkS")
		)
		(fp_line
			(start -0.12065 -0.305054)
			(end -0.12065 -0.2794)
			(stroke
				(width 0.1)
				(type default)
			)
			(layer "F.Fab")
		)
		(fp_line
			(start -0.67945 -0.305054)
			(end -0.12065 -0.305054)
			(stroke
				(width 0.1)
				(type default)
			)
			(layer "F.Fab")
		)
		(fp_line
			(start 0.67945 -0.3048)
			(end 0.67945 0.3048)
			(stroke
				(width 0.1)
				(type default)
			)
			(layer "F.Fab")
		)
		(fp_line
			(start 0.12065 -0.3048)
			(end 0.67945 -0.3048)
			(stroke
				(width 0.1)
				(type default)
			)
			(layer "F.Fab")
		)
		(fp_line
			(start 0.12065 -0.2794)
			(end 0.12065 -0.3048)
			(stroke
				(width 0.1)
				(type default)
			)
			(layer "F.Fab")
		)
		(fp_line
			(start -0.12065 -0.2794)
			(end 0.12065 -0.2794)
			(stroke
				(width 0.1)
				(type default)
			)
			(layer "F.Fab")
		)
		(fp_line
			(start 0.120396 0.2794)
			(end -0.12065 0.2794)
			(stroke
				(width 0.1)
				(type default)
			)
			(layer "F.Fab")
		)
		(fp_line
			(start -0.12065 0.2794)
			(end -0.12065 0.3048)
			(stroke
				(width 0.1)
				(type default)
			)
			(layer "F.Fab")
		)
		(fp_line
			(start 0.67945 0.3048)
			(end 0.120396 0.3048)
			(stroke
				(width 0.1)
				(type default)
			)
			(layer "F.Fab")
		)
		(fp_line
			(start 0.120396 0.3048)
			(end 0.120396 0.2794)
			(stroke
				(width 0.1)
				(type default)
			)
			(layer "F.Fab")
		)
		(fp_line
			(start -0.12065 0.3048)
			(end -0.67945 0.3048)
			(stroke
				(width 0.1)
				(type default)
			)
			(layer "F.Fab")
		)
		(fp_line
			(start -0.67945 0.3048)
			(end -0.67945 -0.305054)
			(stroke
				(width 0.1)
				(type default)
			)
			(layer "F.Fab")
		)
		(pad "1" smd circle
			(at -0.40005 0 90)
			(size 0 0)
			(layers "F.Cu" "F.Mask" "F.Paste")
			(net "FM_P2E_BUF2_EQA0")
		)
		(pad "2" smd circle
			(at 0.40005 0 90)
			(size 0 0)
			(layers "F.Cu" "F.Mask" "F.Paste")
			(net "GND")
		)
	)
	(footprint ""
		(layer "F.Cu")
		(at 356.616 -414.111948 180)
		(property "Reference" "C2343"
			(at 0 0 180)
			(layer "F.SilkS")
			(hide yes)
			(effects
				(font
					(size 1.27 1.27)
				)
			)
		)
		(property "Value" ""
			(at 0 0 180)
			(layer "F.Fab")
			(effects
				(font
					(size 1.27 1.27)
				)
			)
		)
		(duplicate_pad_numbers_are_jumpers no)
		(fp_line
			(start 0.7874 0.4064)
			(end -0.7874 0.4064)
			(stroke
				(width 0.1524)
				(type default)
			)
			(layer "F.SilkS")
		)
		(fp_line
			(start 0.7874 -0.4064)
			(end 0.7874 0.4064)
			(stroke
				(width 0.1524)
				(type default)
			)
			(layer "F.SilkS")
		)
		(fp_line
			(start -0.7874 0.4064)
			(end -0.7874 -0.4064)
			(stroke
				(width 0.1524)
				(type default)
			)
			(layer "F.SilkS")
		)
		(fp_line
			(start -0.7874 -0.4064)
			(end 0.7874 -0.4064)
			(stroke
				(width 0.1524)
				(type default)
			)
			(layer "F.SilkS")
		)
		(fp_line
			(start 0.67945 0.3048)
			(end 0.120396 0.3048)
			(stroke
				(width 0.1)
				(type default)
			)
			(layer "F.Fab")
		)
		(fp_line
			(start 0.67945 -0.3048)
			(end 0.67945 0.3048)
			(stroke
				(width 0.1)
				(type default)
			)
			(layer "F.Fab")
		)
		(fp_line
			(start 0.12065 -0.2794)
			(end 0.12065 -0.3048)
			(stroke
				(width 0.1)
				(type default)
			)
			(layer "F.Fab")
		)
		(fp_line
			(start 0.12065 -0.3048)
			(end 0.67945 -0.3048)
			(stroke
				(width 0.1)
				(type default)
			)
			(layer "F.Fab")
		)
		(fp_line
			(start 0.120396 0.3048)
			(end 0.120396 0.2794)
			(stroke
				(width 0.1)
				(type default)
			)
			(layer "F.Fab")
		)
		(fp_line
			(start 0.120396 0.2794)
			(end -0.12065 0.2794)
			(stroke
				(width 0.1)
				(type default)
			)
			(layer "F.Fab")
		)
		(fp_line
			(start -0.12065 0.3048)
			(end -0.67945 0.3048)
			(stroke
				(width 0.1)
				(type default)
			)
			(layer "F.Fab")
		)
		(fp_line
			(start -0.12065 0.2794)
			(end -0.12065 0.3048)
			(stroke
				(width 0.1)
				(type default)
			)
			(layer "F.Fab")
		)
		(fp_line
			(start -0.12065 -0.2794)
			(end 0.12065 -0.2794)
			(stroke
				(width 0.1)
				(type default)
			)
			(layer "F.Fab")
		)
		(fp_line
			(start -0.12065 -0.305054)
			(end -0.12065 -0.2794)
			(stroke
				(width 0.1)
				(type default)
			)
			(layer "F.Fab")
		)
		(fp_line
			(start -0.67945 0.3048)
			(end -0.67945 -0.305054)
			(stroke
				(width 0.1)
				(type default)
			)
			(layer "F.Fab")
		)
		(fp_line
			(start -0.67945 -0.305054)
			(end -0.12065 -0.305054)
			(stroke
				(width 0.1)
				(type default)
			)
			(layer "F.Fab")
		)
		(pad "1" smd circle
			(at -0.40005 0 180)
			(size 0 0)
			(layers "F.Cu" "F.Mask" "F.Paste")
			(net "SWB_HSC_PWRGD_ISO")
		)
		(pad "2" smd circle
			(at 0.40005 0 180)
			(size 0 0)
			(layers "F.Cu" "F.Mask" "F.Paste")
			(net "GND")
		)
	)
	(footprint ""
		(layer "F.Cu")
		(at 368.75212 -103.866188 90)
		(property "Reference" "C1291"
			(at 0 0 90)
			(layer "F.SilkS")
			(hide yes)
			(effects
				(font
					(size 1.27 1.27)
				)
			)
		)
		(property "Value" ""
			(at 0 0 90)
			(layer "F.Fab")
			(effects
				(font
					(size 1.27 1.27)
				)
			)
		)
		(duplicate_pad_numbers_are_jumpers no)
		(fp_line
			(start 0.7874 -0.4064)
			(end 0.7874 0.4064)
			(stroke
				(width 0.1524)
				(type default)
			)
			(layer "F.SilkS")
		)
		(fp_line
			(start -0.7874 -0.4064)
			(end 0.7874 -0.4064)
			(stroke
				(width 0.1524)
				(type default)
			)
			(layer "F.SilkS")
		)
		(fp_line
			(start 0.7874 0.4064)
			(end -0.7874 0.4064)
			(stroke
				(width 0.1524)
				(type default)
			)
			(layer "F.SilkS")
		)
		(fp_line
			(start -0.7874 0.4064)
			(end -0.7874 -0.4064)
			(stroke
				(width 0.1524)
				(type default)
			)
			(layer "F.SilkS")
		)
		(fp_line
			(start -0.12065 -0.305054)
			(end -0.12065 -0.2794)
			(stroke
				(width 0.1)
				(type default)
			)
			(layer "F.Fab")
		)
		(fp_line
			(start -0.67945 -0.305054)
			(end -0.12065 -0.305054)
			(stroke
				(width 0.1)
				(type default)
			)
			(layer "F.Fab")
		)
		(fp_line
			(start 0.67945 -0.3048)
			(end 0.67945 0.3048)
			(stroke
				(width 0.1)
				(type default)
			)
			(layer "F.Fab")
		)
		(fp_line
			(start 0.12065 -0.3048)
			(end 0.67945 -0.3048)
			(stroke
				(width 0.1)
				(type default)
			)
			(layer "F.Fab")
		)
		(fp_line
			(start 0.12065 -0.2794)
			(end 0.12065 -0.3048)
			(stroke
				(width 0.1)
				(type default)
			)
			(layer "F.Fab")
		)
		(fp_line
			(start -0.12065 -0.2794)
			(end 0.12065 -0.2794)
			(stroke
				(width 0.1)
				(type default)
			)
			(layer "F.Fab")
		)
		(fp_line
			(start 0.120396 0.2794)
			(end -0.12065 0.2794)
			(stroke
				(width 0.1)
				(type default)
			)
			(layer "F.Fab")
		)
		(fp_line
			(start -0.12065 0.2794)
			(end -0.12065 0.3048)
			(stroke
				(width 0.1)
				(type default)
			)
			(layer "F.Fab")
		)
		(fp_line
			(start 0.67945 0.3048)
			(end 0.120396 0.3048)
			(stroke
				(width 0.1)
				(type default)
			)
			(layer "F.Fab")
		)
		(fp_line
			(start 0.120396 0.3048)
			(end 0.120396 0.2794)
			(stroke
				(width 0.1)
				(type default)
			)
			(layer "F.Fab")
		)
		(fp_line
			(start -0.12065 0.3048)
			(end -0.67945 0.3048)
			(stroke
				(width 0.1)
				(type default)
			)
			(layer "F.Fab")
		)
		(fp_line
			(start -0.67945 0.3048)
			(end -0.67945 -0.305054)
			(stroke
				(width 0.1)
				(type default)
			)
			(layer "F.Fab")
		)
		(pad "1" smd circle
			(at -0.40005 0 90)
			(size 0 0)
			(layers "F.Cu" "F.Mask" "F.Paste")
			(net "P3V3_AUX")
		)
		(pad "2" smd circle
			(at 0.40005 0 90)
			(size 0 0)
			(layers "F.Cu" "F.Mask" "F.Paste")
			(net "GND")
		)
	)
	(footprint ""
		(layer "F.Cu")
		(at 446.18783 -378.300234)
		(property "Reference" "C1170"
			(at 0 0 0)
			(layer "F.SilkS")
			(hide yes)
			(effects
				(font
					(size 1.27 1.27)
				)
			)
		)
		(property "Value" ""
			(at 0 0 0)
			(layer "F.Fab")
			(effects
				(font
					(size 1.27 1.27)
				)
			)
		)
		(duplicate_pad_numbers_are_jumpers no)
		(fp_line
			(start -1.524 -0.762)
			(end 1.524 -0.762)
			(stroke
				(width 0.1524)
				(type default)
			)
			(layer "F.SilkS")
		)
		(fp_line
			(start -1.524 0.762)
			(end -1.524 -0.762)
			(stroke
				(width 0.1524)
				(type default)
			)
			(layer "F.SilkS")
		)
		(fp_line
			(start 1.524 -0.762)
			(end 1.524 0.762)
			(stroke
				(width 0.1524)
				(type default)
			)
			(layer "F.SilkS")
		)
		(fp_line
			(start 1.524 0.762)
			(end -1.524 0.762)
			(stroke
				(width 0.1524)
				(type default)
			)
			(layer "F.SilkS")
		)
		(fp_line
			(start -1.1049 -0.724916)
			(end -1.1049 0.724916)
			(stroke
				(width 0.1)
				(type default)
			)
			(layer "F.Fab")
		)
		(fp_line
			(start -1.1049 0.724916)
			(end 1.1049 0.724916)
			(stroke
				(width 0.1)
				(type default)
			)
			(layer "F.Fab")
		)
		(fp_line
			(start 1.1049 -0.724916)
			(end -1.1049 -0.724916)
			(stroke
				(width 0.1)
				(type default)
			)
			(layer "F.Fab")
		)
		(fp_line
			(start 1.1049 0.724916)
			(end 1.1049 -0.724916)
			(stroke
				(width 0.1)
				(type default)
			)
			(layer "F.Fab")
		)
		(pad "1" smd rect
			(at -0.889 0 180)
			(size 1.016 1.27)
			(layers "F.Cu" "F.Mask" "F.Paste")
			(net "P5V_AUX")
		)
		(pad "2" smd rect
			(at 0.889 0 180)
			(size 1.016 1.27)
			(layers "F.Cu" "F.Mask" "F.Paste")
			(net "GND")
		)
	)
)
